# S9S_MB_2U (Grand Teton) — schematic parts with pin connectivity, parts 862–1032 of 6093; source: Cadence DE-HDL packaged netlist (pstxprt.dat, pstxnet.dat, pstchip.dat)

C1097  Q_CAP  0.1UF 6.3V 10% X6S  pkg C0201  page 181 : 1 = USB3_PCH_TX_DN<4> ; 2 = USB3_PCH_TX_C_DN<4>
C1098  Q_CAP_DIFFBUS  DIFF BUS_0.22UF 6.3V 20% X6S  pkg C0201  page 181 : 1 = P3E_PCH_M2_TX_DP<3> ; 2 = P3E_PCH_M2_TX_C_DP<3>
C1099  Q_CAP_DIFFBUS  DIFF BUS_0.22UF 6.3V 20% X6S  pkg C0201  page 181 : 1 = P3E_PCH_M2_TX_DN<3> ; 2 = P3E_PCH_M2_TX_C_DN<3>
C1100  Q_CAP_DIFFBUS  DIFF BUS_0.22UF 6.3V 20% X6S  pkg C0201  page 181 : 1 = P3E_PCH_M2_TX_DP<2> ; 2 = P3E_PCH_M2_TX_C_DP<2>
C1101  Q_CAP_DIFFBUS  DIFF BUS_0.22UF 6.3V 20% X6S  pkg C0201  page 181 : 1 = P3E_PCH_M2_TX_DN<2> ; 2 = P3E_PCH_M2_TX_C_DN<2>
C1102  Q_CAP_DIFFBUS  DIFF BUS_0.22UF 6.3V 20% X6S  pkg C0201  page 181 : 1 = P3E_PCH_M2_TX_DP<1> ; 2 = P3E_PCH_M2_TX_C_DP<1>
C1103  Q_CAP_DIFFBUS  DIFF BUS_0.22UF 6.3V 20% X6S  pkg C0201  page 181 : 1 = P3E_PCH_M2_TX_DN<1> ; 2 = P3E_PCH_M2_TX_C_DN<1>
C1104  Q_CAP_DIFFBUS  DIFF BUS_0.22UF 6.3V 20% X6S  pkg C0201  page 181 : 1 = P3E_PCH_M2_TX_DP<0> ; 2 = P3E_PCH_M2_TX_C_DP<0>
C1105  Q_CAP_DIFFBUS  DIFF BUS_0.22UF 6.3V 20% X6S  pkg C0201  page 181 : 1 = P3E_PCH_M2_TX_DN<0> ; 2 = P3E_PCH_M2_TX_C_DN<0>
C1113  Q_CAP  0.01UF 50V 10% X7R  pkg C0402  page 217 : 1 = P3V3_AUX_FPGA_VCCIO3 ; 2 = GND
C1118  Q_CAP  0.01UF 50V 10% X7R  pkg C0402  page 217 : 1 = P3V3_AUX_FPGA_VCCIO3 ; 2 = GND
C1122  Q_CAP  0.1UF 25V 10% X7R  pkg 0402  page 217 : 1 = P3V3_AUX_FPGA_VCCIO2 ; 2 = GND
C1124  Q_CAP  0.01UF 50V 10% X7R  pkg C0402  page 217 : 1 = P3V3_AUX_FPGA_VCCIO3 ; 2 = GND
C1127  Q_CAP  0.01UF 50V 10% X7R  pkg C0402  page 217 : 1 = P3V3_AUX_FPGA_VCCIO2 ; 2 = GND
C1133  Q_CAP  0.01UF 50V 10% X7R  pkg C0402  page 217 : 1 = P3V3_AUX_FPGA_VCCIO2 ; 2 = GND
C1138  Q_CAP  0.01UF 50V 10% X7R  pkg C0402  page 217 : 1 = P3V3_AUX_FPGA_VCCIO2 ; 2 = GND
C1142  Q_CAP  0.01UF 50V 10% X7R  pkg C0402  page 217 : 1 = P3V3_AUX_FPGA_VCCIO2 ; 2 = GND
C1146  Q_CAP  0.01UF 50V 10% X7R  pkg C0402  page 217 : 1 = P3V3_AUX_FPGA_VCCIO2 ; 2 = GND
C1150  Q_CAP  0.1UF 25V 10% X7R  pkg 0402  page 217 : 1 = VCC_PLD_CORE ; 2 = GND
C1152  Q_CAP  0.01UF 50V 10% X7R  pkg C0402  page 217 : 1 = VCC_PLD_CORE ; 2 = GND
C1154  Q_CAP  0.01UF 50V 10% X7R  pkg C0402  page 217 : 1 = VCC_PLD_CORE ; 2 = GND
C1170  Q_CAP  10UF 16V 10% X6S  pkg C0805  page 260 : 1 = P5V_AUX ; 2 = GND
C1171  Q_CAP  10UF 16V 10% EMPTY  pkg C0805  page 260 : 1 = P5V_AUX ; 2 = GND
C1172  Q_CAP  100NF 50V 10% X7R  pkg C0402  page 260 : 1 = P5V ; 2 = GND
C1173  Q_CAP  0.1UF 25V 10% X7R  pkg 0402  page 155 : 1 = P3V3_AUX ; 2 = GND
C1175  Q_CAP  0.1UF 25V 10% X7R  pkg 0402  page 155 : 1 = P3V3_AUX ; 2 = GND
C1177  Q_CAP  1UF 25V 10% X6S  pkg C0402  page 201 : 1 = RST_RTCRST_N ; 2 = GND
C1178  Q_CAP  22UF 4V 20% X6S  pkg C0603  page 189 : 1 = P1V05_PCH_AUX ; 2 = GND
C1181  Q_CAP  22UF 4V 20% X6S  pkg C0603  page 189 : 1 = P1V8_PCH_AUX ; 2 = GND
C1182  Q_CAP  22UF 4V 20% X6S  pkg C0603  page 189 : 1 = P1V05_PCH_AUX ; 2 = GND
C1183  Q_CAP  2.2UF 10V 10% X6S  pkg C0402  page 189 : 1 = P1V05_PCH_AUX ; 2 = GND
C1184  Q_CAP  22UF 6.3V 20% X6S  pkg C0603  page 189 : 1 = P3V3_AUX ; 2 = GND
C1185  Q_CAP  22UF 4V 20% X6S  pkg C0603  page 189 : 1 = P1V05_PCH_AUX ; 2 = GND
C1186  Q_CAP  22UF 4V 20% X6S  pkg C0603  page 189 : 1 = P1V8_PCH_AUX ; 2 = GND
C1187  Q_CAP  22UF 4V 20% X6S  pkg C0603  page 189 : 1 = P1V05_PCH_AUX ; 2 = GND
C1189  Q_CAP  2.2UF 10V 10% X6S  pkg C0402  page 189 : 1 = P1V05_PCH_AUX ; 2 = GND
C1191  Q_CAP  22UF 6.3V 20% X6S  pkg C0603  page 189 : 1 = P3V3_AUX ; 2 = GND
C1192  Q_CAP  22UF 4V 20% X6S  pkg C0603  page 189 : 1 = P1V05_PCH_AUX ; 2 = GND
C1197  Q_CAP  22UF 4V 20% X6S  pkg C0603  page 189 : 1 = P1V8_PCH_AUX ; 2 = GND
C1198  Q_CAP  22UF 4V 20% X6S  pkg C0603  page 189 : 1 = P1V05_PCH_AUX ; 2 = GND
C1200  Q_CAP  2.2UF 10V 10% X6S  pkg C0402  page 189 : 1 = P1V05_PCH_AUX ; 2 = GND
C1201  Q_CAP  22UF 6.3V 20% X6S  pkg C0603  page 189 : 1 = P3V3_AUX ; 2 = GND
C1202  Q_CAP  22UF 4V 20% X6S  pkg C0603  page 189 : 1 = P1V8_PCH_AUX ; 2 = GND
C1203  Q_CAP  10UF 6.3V 20% X6S  pkg C0402  page 189 : 1 = P1V05_PCH_AUX ; 2 = GND
C1204  Q_CAP  2.2UF 10V 10% X6S  pkg C0402  page 189 : 1 = P1V05_PCH_AUX ; 2 = GND
C1205  Q_CAP  10UF 6.3V 20% X6S  pkg C0402  page 189 : 1 = P1V05_PCH_AUX ; 2 = GND
C1206  Q_CAP  10UF 6.3V 20% X6S  pkg C0402  page 189 : 1 = P3V3_AUX ; 2 = GND
C1207  Q_CAP  10UF 6.3V 20% X6S  pkg C0402  page 189 : 1 = P1V8_PCH_AUX ; 2 = GND
C1209  Q_CAP  100PF 50V 5% NPO  pkg 0402  page 220 : 1 = PWRGD_SYS_PWROK_R ; 2 = GND
C1210  Q_CAP  10UF 6.3V 20% X6S  pkg C0402  page 189 : 1 = P1V05_PCH_AUX ; 2 = GND
C1211  Q_CAP  100PF 50V 5% NPO  pkg 0402  page 220 : 1 = PWRGD_PCH_PWROK_R ; 2 = GND
C1213  Q_CAP  22UF 16V 20% X6S  pkg C0805  page 153 : 1 = P12V_OCP_SFF ; 2 = GND
C1214  Q_CAP  2.2UF 10V 10% X6S  pkg C0402  page 189 : 1 = P1V05_PCH_AUX ; 2 = GND
C1226  Q_CAP  0.22UF 25V 10% X7R  pkg C0402  page 260 : 1 = VR_P5V_EN_D_R ; 2 = GND
C1227  Q_CAP  100NF 50V 10% X7R  pkg C0402  page 260 : 1 = P5V ; 2 = GND
C1228  Q_CAP  10UF 6.3V 20% X6S  pkg C0402  page 189 : 1 = P1V05_PCH_AUX ; 2 = GND
C1231  Q_CAP  10UF 6.3V 20% X6S  pkg C0402  page 189 : 1 = P1V05_PCH_AUX ; 2 = GND
C1232  Q_CAP  22UF 16V 20% X6S  pkg C0805  page 153 : 1 = P12V_OCP_SFF ; 2 = GND
C1233  Q_CAP  0.1UF 25V 10% X7R  pkg 0402  page 153 : 1 = P12V_OCP_SFF ; 2 = GND
C1234  Q_CAP  0.1UF 25V 10% X7R  pkg 0402  page 153 : 1 = P12V_OCP_SFF ; 2 = GND
C1235  Q_CAP  0.1UF 25V 10% X7R  pkg 0402  page 153 : 1 = P12V_OCP_SFF ; 2 = GND
C1236  Q_CAP  0.1UF 25V 10% X7R  pkg 0402  page 153 : 1 = P12V_OCP_SFF ; 2 = GND
C1237  Q_CAP  0.1UF 25V 10% X7R  pkg 0402  page 153 : 1 = P3V3_OCP_SFF ; 2 = GND
C1238  Q_CAP  0.1UF 25V 10% X7R  pkg 0402  page 153 : 1 = P3V3_OCP_SFF ; 2 = GND
C1239  Q_CAP  0.1UF 25V 10% X7R  pkg 0402  page 153 : 1 = P3V3_OCP_SFF ; 2 = GND
C1240  Q_CAP  0.1UF 25V 10% X7R  pkg 0402  page 153 : 1 = P3V3_OCP_SFF ; 2 = GND
C1242  Q_CAP  2.2UF 10V 10% X6S  pkg C0402  page 189 : 1 = P1V05_PCH_AUX ; 2 = GND
C1243  Q_CAP  47UF 6.3V 20% X6S  pkg C0805  page 189 : 1 = P3V3_AUX ; 2 = GND
C1244  Q_CAP  47UF 4V 20% X6S  pkg C0805  page 189 : 1 = P1V05_PCH_AUX ; 2 = GND
C1245  Q_CAP  47UF 6.3V 20% X6S  pkg C0805  page 189 : 1 = P3V3_AUX ; 2 = GND
C1246  Q_CAP  47UF 4V 20% X6S  pkg C0805  page 189 : 1 = P1V05_PCH_AUX ; 2 = GND
C1247  Q_CAP  47UF 4V 20% X6S  pkg C0805  page 189 : 1 = P1V05_PCH_AUX ; 2 = GND
C1248  Q_CAP  47UF 4V 20% X6S  pkg C0805  page 189 : 1 = P1V05_PCH_AUX ; 2 = GND
C1249  Q_CAP  47UF 4V 20% X6S  pkg C0805  page 189 : 1 = P1V05_PCH_AUX ; 2 = GND
C1250  Q_CAP  1UF 6.3V 10% EMPTY  pkg 0402  page 189 : 1 = P1V05_PCH_AUX ; 2 = GND
C1251  Q_CAP  10UF 6.3V 20% X6S  pkg C0603  page 189 : 1 = P1V05_PCH_PLL_AUX ; 2 = GND
C1252  Q_CAP  10UF 6.3V 20% X6S  pkg C0603  page 189 : 1 = P1V8_PCH_PLL_AUX ; 2 = GND
C1253  Q_CAP  1UF 6.3V 10% EMPTY  pkg 0402  page 189 : 1 = P1V8_PCH_AUX ; 2 = GND
C1254  Q_CAP  10UF 6.3V 20% X6S  pkg C0603  page 189 : 1 = P1V05_PCH_PLL_AUX ; 2 = GND
C1255  Q_CAP  10UF 6.3V 20% X6S  pkg C0603  page 189 : 1 = P1V8_PCH_PLL_AUX ; 2 = GND
C1256  Q_CAP  1UF 6.3V 10% EMPTY  pkg 0402  page 189 : 1 = P1V05_PCH_PLL_AUX ; 2 = GND
C1257  Q_CAP  1UF 6.3V 10% EMPTY  pkg 0402  page 189 : 1 = P1V8_PCH_PLL_AUX ; 2 = GND
C1258  Q_CAP  47UF 4V 20% X6S  pkg C0805  page 189 : 1 = P1V05_PCH_PLL_AUX ; 2 = GND
C1259  Q_CAP  47UF 4V 20% X6S  pkg C0805  page 189 : 1 = P1V8_PCH_PLL_AUX ; 2 = GND
C1260  Q_CAP  10UF 6.3V 20% X6S  pkg C0603  page 189 : 1 = P1V05_PCH_PLL_AUX ; 2 = GND
C1261  Q_CAP  10UF 6.3V 20% X6S  pkg C0603  page 189 : 1 = P1V8_PCH_PLL_AUX ; 2 = GND
C1262  Q_CAP  10UF 6.3V 20% X6S  pkg C0402  page 189 : 1 = P1V05_PCH_PLL_AUX ; 2 = GND
C1263  Q_CAP  10UF 6.3V 20% X6S  pkg C0402  page 189 : 1 = P1V8_PCH_PLL_AUX ; 2 = GND
C1264  Q_CAP  1UF 6.3V 10% EMPTY  pkg 0402  page 189 : 1 = P1V05_PCH_PLL_AUX ; 2 = GND
C1265  Q_CAP  1UF 6.3V 10% EMPTY  pkg 0402  page 189 : 1 = P1V8_PCH_PLL_AUX ; 2 = GND
C1266  Q_CAP  10UF 6.3V 20% X6S  pkg C0402  page 189 : 1 = P1V8_PCH_PLL_AUX ; 2 = GND
C1272  Q_CAP  47UF 4V 20% X6S  pkg C0805  page 189 : 1 = P1V05_PCH_PLL_AUX ; 2 = GND
C1273  Q_CAP  47UF 4V 20% X6S  pkg C0805  page 189 : 1 = P1V8_PCH_PLL_AUX ; 2 = GND
C1274  Q_CAP  0.1UF 25V 10% X7R  pkg 0402  page 155 : 1 = P3V3_AUX ; 2 = GND
C1275  Q_CAP  0.1UF 25V 10% X7R  pkg 0402  page 155 : 1 = P3V3_AUX ; 2 = GND
C1276  Q_CAP  22UF 16V 20% X6S  pkg C0805  page 191 : 1 = P12V_E1S_0 ; 2 = GND
C1277  Q_CAP  22UF 16V 20% X6S  pkg C0805  page 191 : 1 = P12V_E1S_0 ; 2 = GND
C1278  Q_CAP  0.1UF 25V 10% X7R  pkg 0402  page 191 : 1 = P12V_E1S_0 ; 2 = GND
C1279  Q_CAP  0.1UF 25V 10% X7R  pkg 0402  page 191 : 1 = P12V_E1S_0 ; 2 = GND
C1282  Q_CAP  0.1UF 25V 10% X7R  pkg 0402  page 191 : 1 = P3V3_E1S_0 ; 2 = GND
C1283  Q_CAP  0.1UF 25V 10% X7R  pkg 0402  page 191 : 1 = P3V3_E1S_0 ; 2 = GND
C1288  Q_CAP  0.1UF 25V 10% X7R  pkg 0402  page 134 : 1 = P3V3_AUX ; 2 = GND
C1289  Q_CAP  1UF 25V 10% X6S  pkg C0402  page 134 : 1 = P3V3_AUX ; 2 = GND
C1290  Q_CAP  1UF 25V 10% X6S  pkg C0402  page 239 : 1 = P3V3_AUX ; 2 = GND
C1291  Q_CAP  1UF 25V 10% X6S  pkg C0402  page 239 : 1 = P3V3_AUX ; 2 = GND
C1292  Q_CAP  0.1UF 25V 10% X7R  pkg 0402  page 134 : 1 = P3V3_AUX ; 2 = GND
C1293  Q_CAP  1UF 25V 10% X6S  pkg C0402  page 134 : 1 = FM_BMC_EN_DET ; 2 = GND
C1296  Q_CAP  1000PF 50V 5% X7R  pkg 0402  page 282 : 1 = PWRGD_PVNN_MAIN_CPU0 ; 2 = GND
C1297  Q_CAP  1000PF 50V 5% X7R  pkg 0402  page 300 : 1 = PWRGD_PVNN_MAIN_CPU1 ; 2 = GND
C1300  Q_CAP  1000PF 50V 5% EMPTY  pkg 0402  page 281 : 1 = FM_PVPP_HBM_CPU0_EN ; 2 = GND
C1301  Q_CAP  1000PF 50V 5% X7R  pkg 0402  page 281 : 1 = PWRGD_PVPP_HBM_CPU0_R ; 2 = GND
C1302  Q_CAP  22UF 4V 20% X6S  pkg C0402  page 240 : 1 = PVNN_TERM_CPU0 ; 2 = GND
C1305  Q_CAP  0.1UF 25V 10% X7R  pkg 0402  page 194 : 1 = P3V3_AUX ; 2 = GND
C1307  Q_CAP  1000PF 50V 5% EMPTY  pkg 0402  page 282 : 1 = FM_PVNN_MAIN_CPU0_EN ; 2 = GND
C1308  Q_CAP  1000PF 50V 5% EMPTY  pkg 0402  page 300 : 1 = FM_PVNN_MAIN_CPU1_EN ; 2 = GND
C1309  Q_CAP  10UF 6.3V 20% X6S  pkg C0603  page 210 : 1 = P3V3_AUX_CLK_GEN_VDDXTAL_CK440 ; 2 = GND
C1310  Q_CAP  10UF 6.3V 20% X6S  pkg C0603  page 210 : 1 = P3V3_AUX_CLK_GEN_VDDMXCK_CK440 ; 2 = GND
C1311  Q_CAP  1UF 25V 10% X6S  pkg C0402  page 210 : 1 = P3V3_AUX_CLK_GEN_VDDXTAL_CK440 ; 2 = GND
C1312  Q_CAP  1UF 25V 10% X6S  pkg C0402  page 210 : 1 = P3V3_AUX_CLK_GEN_VDDMXCK_CK440 ; 2 = GND
C1313  Q_CAP  10UF 6.3V 20% X6S  pkg C0603  page 210 : 1 = P3V3_AUX_CLK_GEN_VDDA25M_CK440 ; 2 = GND
C1314  Q_CAP  10UF 6.3V 20% X6S  pkg C0603  page 210 : 1 = P3V3_AUX_CLK_GEN_VDDPT_CK440 ; 2 = GND
C1315  Q_CAP  1UF 25V 10% X6S  pkg C0402  page 244 : 1 = P3V3_AUX ; 2 = GND
C1316  Q_CAP  0.047UF 25V 10% X7R  pkg C0402  page 244 : 1 = FM_COMP_P3V3_STBY_CEXT ; 2 = GND
C1317  Q_CAP  0.1UF 25V 10% X7R  pkg 0402  page 244 : 1 = P3V3_AUX ; 2 = GND
C1318  Q_CAP  1UF 25V 10% EMPTY  pkg C0402  page 244 : 1 = PWRGD_DSW_PWROK_R1 ; 2 = GND
C1319  Q_CAP  1UF 25V 10% X6S  pkg C0402  page 244 : 1 = PWRGD_DSW_PWROK ; 2 = GND
C1320  Q_CAP  0.1UF 25V 10% X7R  pkg 0402  page 214 : 1 = P3V3_AUX ; 2 = GND
C1321  Q_CAP  0.1UF 25V 10% X7R  pkg 0402  page 239 : 1 = P3V3_AUX ; 2 = GND
C1322  Q_CAP  0.1UF 25V 10% X7R  pkg 0402  page 239 : 1 = P3V3_AUX ; 2 = GND
C1323  Q_CAP  0.1UF 25V 10% X7R  pkg 0402  page 194 : 1 = P1V8_PCH_AUX ; 2 = GND
C1324  Q_CAP  0.1UF 25V 10% EMPTY  pkg 0402  page 208 : 1 = FM_CK440Q_DEV_25M_EN ; 2 = GND
C1325  Q_CAP  0.1UF 25V 10% X7R  pkg 0402  page 215 : 1 = FM_PLD_REV_N ; 2 = GND
C1331  Q_CAP  10UF 16V 10% X6S  pkg C0805  page 260 : 1 = P5V ; 2 = GND
C1332  Q_CAP  100NF 50V 10% X7R  pkg C0402  page 260 : 1 = P3V3_AUX ; 2 = GND
C1333  Q_CAP  10UF 16V 10% X6S  pkg C0805  page 260 : 1 = P3V3_AUX ; 2 = GND
C1336  Q_CAP  10UF 6.3V 20% X6S  pkg C0402  page 296 : 1 = PVNN_TERM_CPU1 ; 2 = GND
C1337  Q_CAP  0.1UF 25V 10% X7R  pkg 0402  page 296 : 1 = PVNN_TERM_CPU1 ; 2 = GND
C1338  Q_CAP  10UF 16V 10% EMPTY  pkg C0805  page 260 : 1 = P3V3_AUX ; 2 = GND
C1339  Q_CAP  100NF 50V 10% X7R  pkg C0402  page 260 : 1 = P3V3 ; 2 = GND
C1340  Q_CAP  10UF 16V 10% X6S  pkg C0805  page 260 : 1 = P3V3 ; 2 = GND
C1344  Q_CAP  100PF 50V 5% EMPTY  pkg 0402  page 250 : 1 = P12V_AUX_ADC_MAM ; 2 = GND
C1347  Q_CAP  0.1UF 25V 10% EMPTY  pkg 0402  page 250 : 1 = MAX11617_VREF ; 2 = GND
C1353  Q_CAP  22UF 4V 20% X6S  pkg C0402  page 79 : 1 = PVNN_MAIN_CPU1 ; 2 = GND
C1362  Q_CAP  22UF 4V 20% X6S  pkg C0402  page 76 : 1 = PVNN_MAIN_CPU0 ; 2 = GND
C1363  Q_CAP  22UF 4V 20% X6S  pkg C0402  page 80 : 1 = PVNN_MAIN_CPU0 ; 2 = GND
C1364  Q_CAP  22UF 4V 20% X6S  pkg C0402  page 80 : 1 = PVNN_MAIN_CPU0 ; 2 = GND
C1365  Q_CAP  22UF 4V 20% X6S  pkg C0402  page 80 : 1 = PVNN_MAIN_CPU1 ; 2 = GND
C1366  Q_CAP  22UF 4V 20% X6S  pkg C0402  page 80 : 1 = PVNN_MAIN_CPU1 ; 2 = GND
C1387  Q_CAP  47UF 4V 20% X6S  pkg C0805  page 78 : 1 = PVNN_MAIN_CPU1 ; 2 = GND
C1388  Q_CAP  47UF 4V 20% X6S  pkg C0805  page 78 : 1 = PVPP_HBM_CPU1 ; 2 = GND
C1389  Q_CAP  47UF 2.5V 20% X6S  pkg C0603  page 78 : 1 = PVNN_MAIN_CPU1 ; 2 = GND
C1390  Q_CAP  47UF 4V 20% X6S  pkg C0805  page 78 : 1 = PVPP_HBM_CPU1 ; 2 = GND
C1391  Q_CAP  47UF 2.5V 20% X6S  pkg C0603  page 78 : 1 = PVNN_MAIN_CPU1 ; 2 = GND
C1392  Q_CAP  47UF 4V 20% X6S  pkg C0805  page 78 : 1 = PVPP_HBM_CPU1 ; 2 = GND
C1393  Q_CAP  47UF 2.5V 20% X6S  pkg C0603  page 78 : 1 = PVNN_MAIN_CPU1 ; 2 = GND
C1396  Q_CAP  47UF 4V 20% X6S  pkg C0805  page 75 : 1 = PVPP_HBM_CPU0 ; 2 = GND
C1397  Q_CAP  47UF 4V 20% X6S  pkg C0805  page 75 : 1 = PVPP_HBM_CPU0 ; 2 = GND
C1398  Q_CAP  47UF 4V 20% X6S  pkg C0805  page 75 : 1 = PVPP_HBM_CPU0 ; 2 = GND
C1399  Q_CAP  47UF 4V 20% X6S  pkg C0805  page 76 : 1 = PVNN_MAIN_CPU0 ; 2 = GND
C1400  Q_CAP  47UF 4V 20% X6S  pkg C0805  page 76 : 1 = PVNN_MAIN_CPU0 ; 2 = GND
C1403  Q_CAP  47UF 4V 20% X6S  pkg C0805  page 79 : 1 = PVNN_MAIN_CPU1 ; 2 = GND
C1404  Q_CAP  47UF 4V 20% X6S  pkg C0805  page 79 : 1 = PVNN_MAIN_CPU1 ; 2 = GND
C1405  Q_CAP  47UF 2.5V 20% X6S  pkg C0603  page 75 : 1 = PVNN_MAIN_CPU0 ; 2 = GND
C1406  Q_CAP  47UF 2.5V 20% X6S  pkg C0603  page 75 : 1 = PVNN_MAIN_CPU0 ; 2 = GND
C1407  Q_CAP  47UF 2.5V 20% X6S  pkg C0603  page 75 : 1 = PVNN_MAIN_CPU0 ; 2 = GND
C1409  Q_CAP  10UF 6.3V 20% X6S  pkg C0603  page 206 : 1 = P3V3_DB2000_VDD ; 2 = GND
C1436  Q_CAP  0.22UF 6.3V 10% X6S  pkg C0201  page 75 : 1 = PVPP_HBM_CPU0 ; 2 = GND
C1437  Q_CAP  0.22UF 6.3V 10% X6S  pkg C0201  page 78 : 1 = PVPP_HBM_CPU1 ; 2 = GND
C1507  Q_CAP  18PF 50V 5% C0G  pkg 0402  page 179 : 1 = XTAL_PCH_RTC2_R ; 2 = GND
C1508  Q_CAP  18PF 50V 5% C0G  pkg 0402  page 179 : 1 = XTAL_PCH_RTC1 ; 2 = GND
C1516  Q_CAP_DIFFBUS  DIFF BUS_0.22UF 6.3V 20% X6S  pkg C0201  page 177 : 1 = P5E_CPU1_PE3_TX_C_DN<15> ; 2 = P5E_CPU1_PE3_TX_DN<15>
